# BARRELEYE_G2-FPDB_POST-EVT-HW-EBOM-X00_20161123-add_2nd_source_X08-20161215-Final-b.xls — DEPOP_GA (bom)
| FOXCONN TECHNOLOGY GROUP |  |  |  |  |  |  |  |  |  |  |  |  |
| BILL OF MATERIAL |  |  |  |  |  |  |  |  |  |  |  |  |
| REV OF  BOM |  | CUSTOMER | <name> |  | CUSTOMER P/N |  | PRODUCT CODE |  | PWA  REV |  | DATE |  |
| Sourcing (Single/Sole/Multi) | Critical Commodity (Y or N) | Component Class (1, 2, other) | Customer PSL (Y or N) | Item Number | Foxconn P/N | Customer P/N | Part Description | Manufacturer  Full Name | Manufacturer  Part Number | Qty | RoHS Status | Location |
